# SCM (Grand Teton) — schematic netlist excerpt (pin names and nets, part order shuffled) for the footprints in the layout excerpt that follows; sources: Cadence DE-HDL packaged netlist, KiCad conversion of 12092022_DA0F0TMDCD0_F0T_Management_Board_D_brd_V3_OCP.brd

U39  RT9059GQW  IC  pkg DFN10_THXE  page 53
  VOUT1  = P2V5_AUX
  VOUT2  = P2V5_AUX
  VOUT3  = P2V5_AUX
  ADJ  = U39_ADJ
  PGOOD  = PWRGD_P2V5_AUX_R
  EN  = PWRGD_P3V3_AUX_R2
  VIN1  = P3V3_AUX
  VIN2  = P3V3_AUX
  VIN3  = P3V3_AUX
  VDD  = P5V_AUX
  EP  = GND

R438  Q_RES  2.2K 5% CHIP  pkg 0402LF  page 27 : A = P3V3_AUX ; B = SMB_BMC_MM14_SDA

(kicad_pcb
	(version 20260206)
	(generator "pcbnew")
	(generator_version "10.0")
	(general
		(thickness 1.6)
		(legacy_teardrops no)
	)
	(paper "A4")
	(title_block
		(title "12092022_DA0F0TMDCD0_F0T_Management_Board_D_brd_V3_OCP.brd")
		(comment 1 "Grand Teton / footprints 354-355 of 1440")
	)
	(layers
		(0 "F.Cu" signal "TOP")
		(4 "In1.Cu" signal "GND")
		(6 "In2.Cu" signal "IN1")
		(8 "In3.Cu" signal "GND1")
		(10 "In4.Cu" signal "IN2")
		(12 "In5.Cu" signal "VCC")
		(14 "In6.Cu" signal "VCC1")
		(16 "In7.Cu" signal "IN3")
		(18 "In8.Cu" signal "GND2")
		(20 "In9.Cu" signal "IN4")
		(22 "In10.Cu" signal "GND3")
		(2 "B.Cu" signal "BOTTOM")
		(9 "F.Adhes" user "F.Adhesive")
		(11 "B.Adhes" user "B.Adhesive")
		(13 "F.Paste" user "Package Geometry/Pastemask Top")
		(15 "B.Paste" user "Package Geometry/Pastemask Bottom")
		(5 "F.SilkS" user "Ref Des/Silkscreen Top")
		(7 "B.SilkS" user "Ref Des/Silkscreen Bottom")
		(1 "F.Mask" user "Board Geometry/Soldermask Top")
		(3 "B.Mask" user "Board Geometry/Soldermask Bottom")
		(17 "Dwgs.User" user "User.Drawings")
		(19 "Cmts.User" user "User.Comments")
		(21 "Eco1.User" user "User.Eco1")
		(23 "Eco2.User" user "User.Eco2")
		(25 "Edge.Cuts" user "Board Geometry/Outline")
		(27 "Margin" user)
		(31 "F.CrtYd" user "Package Geometry/Place Bound Top")
		(29 "B.CrtYd" user "Package Geometry/Place Bound Bottom")
		(35 "F.Fab" user "Ref Des/Assembly Top")
		(33 "B.Fab" user "Ref Des/Assembly Bottom")
	)
	(footprint ""
		(layer "F.Cu")
		(at 36.1061 -47.13605 -90)
		(property "Reference" "R438"
			(at 0 0 270)
			(layer "F.SilkS")
			(hide yes)
			(effects
				(font
					(size 1.27 1.27)
				)
			)
		)
		(property "Value" ""
			(at 0 0 270)
			(layer "F.Fab")
			(effects
				(font
					(size 1.27 1.27)
				)
			)
		)
		(duplicate_pad_numbers_are_jumpers no)
		(fp_line
			(start -0.7874 0.4064)
			(end -0.7874 -0.4064)
			(stroke
				(width 0.1524)
				(type default)
			)
			(layer "F.SilkS")
		)
		(fp_line
			(start 0.7874 0.4064)
			(end -0.7874 0.4064)
			(stroke
				(width 0.1524)
				(type default)
			)
			(layer "F.SilkS")
		)
		(fp_line
			(start -0.7874 -0.4064)
			(end 0.7874 -0.4064)
			(stroke
				(width 0.1524)
				(type default)
			)
			(layer "F.SilkS")
		)
		(fp_line
			(start 0.7874 -0.4064)
			(end 0.7874 0.4064)
			(stroke
				(width 0.1524)
				(type default)
			)
			(layer "F.SilkS")
		)
		(fp_line
			(start -0.67945 0.3048)
			(end -0.67945 -0.305054)
			(stroke
				(width 0.1)
				(type default)
			)
			(layer "F.Fab")
		)
		(fp_line
			(start -0.12065 0.3048)
			(end -0.67945 0.3048)
			(stroke
				(width 0.1)
				(type default)
			)
			(layer "F.Fab")
		)
		(fp_line
			(start 0.120396 0.3048)
			(end 0.120396 0.2794)
			(stroke
				(width 0.1)
				(type default)
			)
			(layer "F.Fab")
		)
		(fp_line
			(start 0.67945 0.3048)
			(end 0.120396 0.3048)
			(stroke
				(width 0.1)
				(type default)
			)
			(layer "F.Fab")
		)
		(fp_line
			(start -0.12065 0.2794)
			(end -0.12065 0.3048)
			(stroke
				(width 0.1)
				(type default)
			)
			(layer "F.Fab")
		)
		(fp_line
			(start 0.120396 0.2794)
			(end -0.12065 0.2794)
			(stroke
				(width 0.1)
				(type default)
			)
			(layer "F.Fab")
		)
		(fp_line
			(start -0.12065 -0.2794)
			(end 0.12065 -0.2794)
			(stroke
				(width 0.1)
				(type default)
			)
			(layer "F.Fab")
		)
		(fp_line
			(start 0.12065 -0.2794)
			(end 0.12065 -0.3048)
			(stroke
				(width 0.1)
				(type default)
			)
			(layer "F.Fab")
		)
		(fp_line
			(start 0.12065 -0.3048)
			(end 0.67945 -0.3048)
			(stroke
				(width 0.1)
				(type default)
			)
			(layer "F.Fab")
		)
		(fp_line
			(start 0.67945 -0.3048)
			(end 0.67945 0.3048)
			(stroke
				(width 0.1)
				(type default)
			)
			(layer "F.Fab")
		)
		(fp_line
			(start -0.67945 -0.305054)
			(end -0.12065 -0.305054)
			(stroke
				(width 0.1)
				(type default)
			)
			(layer "F.Fab")
		)
		(fp_line
			(start -0.12065 -0.305054)
			(end -0.12065 -0.2794)
			(stroke
				(width 0.1)
				(type default)
			)
			(layer "F.Fab")
		)
		(pad "1" smd circle
			(at -0.40005 0 270)
			(size 0 0)
			(layers "F.Cu" "F.Mask" "F.Paste")
			(net "P3V3_AUX")
		)
		(pad "2" smd circle
			(at 0.40005 0 270)
			(size 0 0)
			(layers "F.Cu" "F.Mask" "F.Paste")
			(net "SMB_BMC_MM14_SDA")
		)
	)
	(footprint ""
		(layer "F.Cu")
		(at 82.639662 -33.580324 -90)
		(property "Reference" "U39"
			(at 0.409448 2.049272 90)
			(unlocked yes)
			(layer "F.SilkS")
			(effects
				(font
					(size 0.7874 0.5842)
					(thickness 0.1524)
				)
				(justify left)
			)
		)
		(property "Value" ""
			(at 0 0 270)
			(layer "F.Fab")
			(effects
				(font
					(size 1.27 1.27)
				)
			)
		)
		(duplicate_pad_numbers_are_jumpers no)
		(fp_line
			(start -1.525016 1.525016)
			(end -0.889 1.525016)
			(stroke
				(width 0.1524)
				(type default)
			)
			(layer "F.SilkS")
		)
		(fp_line
			(start 0.9906 1.525016)
			(end 1.525016 1.525016)
			(stroke
				(width 0.1524)
				(type default)
			)
			(layer "F.SilkS")
		)
		(fp_line
			(start 1.525016 1.525016)
			(end -1.525016 1.525016)
			(stroke
				(width 0.1524)
				(type default)
			)
			(layer "F.SilkS")
		)
		(fp_line
			(start 1.525016 1.525016)
			(end 1.525016 1.3208)
			(stroke
				(width 0.1524)
				(type default)
			)
			(layer "F.SilkS")
		)
		(fp_line
			(start -1.525016 1.3208)
			(end -1.525016 1.525016)
			(stroke
				(width 0.1524)
				(type default)
			)
			(layer "F.SilkS")
		)
		(fp_line
			(start 1.525016 -1.3208)
			(end 1.525016 -1.525016)
			(stroke
				(width 0.1524)
				(type default)
			)
			(layer "F.SilkS")
		)
		(fp_line
			(start -1.525016 -1.525016)
			(end -1.525016 -1.3208)
			(stroke
				(width 0.1524)
				(type default)
			)
			(layer "F.SilkS")
		)
		(fp_line
			(start -0.8636 -1.525016)
			(end -1.525016 -1.525016)
			(stroke
				(width 0.1524)
				(type default)
			)
			(layer "F.SilkS")
		)
		(fp_line
			(start 1.525016 -1.525016)
			(end -1.525016 -1.525016)
			(stroke
				(width 0.1524)
				(type default)
			)
			(layer "F.SilkS")
		)
		(fp_line
			(start 1.525016 -1.525016)
			(end 0.9398 -1.525016)
			(stroke
				(width 0.1524)
				(type default)
			)
			(layer "F.SilkS")
		)
		(fp_poly
			(pts
				(xy -2.089404 -1.1684) (xy -2.513838 -2.017014) (xy -2.938272 -1.592834)
			)
			(stroke
				(width 0)
				(type default)
			)
			(fill yes)
			(layer "F.SilkS")
		)
		(fp_line
			(start -1.525016 1.525016)
			(end -1.525016 -1.525016)
			(stroke
				(width 0.1)
				(type default)
			)
			(layer "F.Fab")
		)
		(fp_line
			(start 1.525016 1.525016)
			(end -1.525016 1.525016)
			(stroke
				(width 0.1)
				(type default)
			)
			(layer "F.Fab")
		)
		(fp_line
			(start -1.525016 -1.525016)
			(end 1.525016 -1.525016)
			(stroke
				(width 0.1)
				(type default)
			)
			(layer "F.Fab")
		)
		(fp_line
			(start 1.525016 -1.525016)
			(end 1.525016 1.525016)
			(stroke
				(width 0.1)
				(type default)
			)
			(layer "F.Fab")
		)
		(fp_poly
			(pts
				(xy -2.0701 -0.999998) (xy -2.977896 -1.302512) (xy -2.977896 -0.697484)
			)
			(stroke
				(width 0)
				(type default)
			)
			(fill yes)
			(layer "F.Fab")
		)
		(pad "1" smd rect
			(at -1.550162 -0.999998 180)
			(size 0.2794 0.9144)
			(layers "F.Cu" "F.Mask" "F.Paste")
			(net "P2V5_AUX")
		)
		(pad "2" smd rect
			(at -1.550162 -0.500126 180)
			(size 0.2794 0.9144)
			(layers "F.Cu" "F.Mask" "F.Paste")
			(net "P2V5_AUX")
		)
		(pad "3" smd rect
			(at -1.550162 0 180)
			(size 0.2794 0.9144)
			(layers "F.Cu" "F.Mask" "F.Paste")
			(net "P2V5_AUX")
		)
		(pad "4" smd rect
			(at -1.550162 0.500126 180)
			(size 0.2794 0.9144)
			(layers "F.Cu" "F.Mask" "F.Paste")
			(net "U39_ADJ")
		)
		(pad "5" smd rect
			(at -1.550162 0.999998)
			(size 0.2794 0.9144)
			(layers "F.Cu" "F.Mask" "F.Paste")
			(net "PWRGD_P2V5_AUX_R")
		)
		(pad "6" smd rect
			(at 1.550162 0.999998)
			(size 0.2794 0.9144)
			(layers "F.Cu" "F.Mask" "F.Paste")
			(net "PWRGD_P3V3_AUX_R2")
		)
		(pad "7" smd rect
			(at 1.550162 0.500126 180)
			(size 0.2794 0.9144)
			(layers "F.Cu" "F.Mask" "F.Paste")
			(net "P3V3_AUX")
		)
		(pad "8" smd rect
			(at 1.550162 0 180)
			(size 0.2794 0.9144)
			(layers "F.Cu" "F.Mask" "F.Paste")
			(net "P3V3_AUX")
		)
		(pad "9" smd rect
			(at 1.550162 -0.500126 180)
			(size 0.2794 0.9144)
			(layers "F.Cu" "F.Mask" "F.Paste")
			(net "P3V3_AUX")
		)
		(pad "10" smd rect
			(at 1.550162 -0.999998 180)
			(size 0.2794 0.9144)
			(layers "F.Cu" "F.Mask" "F.Paste")
			(net "P5V_AUX")
		)
		(pad "TH" smd rect
			(at 0 0 270)
			(size 1.7526 2.667)
			(layers "F.Cu" "F.Mask" "F.Paste")
			(net "GND")
		)
		(zone
			(layer "F.Cu")
			(hatch none 0.5)
			(connect_pads
				(clearance 0)
			)
			(min_thickness 0.25)
			(keepout
				(tracks not_allowed)
				(vias allowed)
				(pads allowed)
				(copperpour not_allowed)
				(footprints allowed)
			)
			(placement
				(enabled no)
				(sheetname "")
			)
			(fill
				(thermal_gap 0.5)
				(thermal_bridge_width 0.5)
				(island_removal_mode 0)
			)
			(polygon
				(pts
					(xy 84.17306 -34.597086) (xy 81.12506 -34.597086) (xy 81.12506 -32.565086) (xy 84.17306 -32.565086)
					(xy 84.17306 -34.495486) (xy 84.04606 -34.495486) (xy 84.04606 -32.641286) (xy 81.22666 -32.641286)
					(xy 81.22666 -34.520886) (xy 84.17306 -34.520886)
				)
			)
		)
	)
)
